FILE_TYPE=LIBRARY_PARTS;
primitive 'W25Q128','W25Q128_SOIC';
  pin
    'CLK':
      PIN_NUMBER='(16)';
      INPUT_LOAD='(-0.01,0.01)';
    'CS_N':
      PIN_NUMBER='(7)';
      INPUT_LOAD='(-0.01,0.01)';
    'DI_IO0':
      PIN_NUMBER='(15)';
      BIDIRECTIONAL='TRUE';
      INPUT_LOAD='(-0.01,0.01)';
      OUTPUT_LOAD='(1.0,-1.0)';
    'DO_IO1':
      PIN_NUMBER='(8)';
      BIDIRECTIONAL='TRUE';
      INPUT_LOAD='(-0.01,0.01)';
      OUTPUT_LOAD='(1.0,-1.0)';
    'GND':
      PIN_NUMBER='(10)';
      PINUSE='GROUND';
      NO_LOAD_CHECK='Both';
      NO_IO_CHECK='Both';
      NO_ASSERT_CHECK='TRUE';
      NO_DIR_CHECK='TRUE';
      ALLOW_CONNECT='TRUE';
    'HOLD_N_IO3':
      PIN_NUMBER='(1)';
      BIDIRECTIONAL='TRUE';
      INPUT_LOAD='(-0.01,0.01)';
      OUTPUT_LOAD='(1.0,-1.0)';
    'NC'<7>:
      PIN_NUMBER='(14)';
      PINUSE='NC';
      NO_LOAD_CHECK='BOTH';
      NO_IO_CHECK='BOTH';
      ALLOW_CONNECT='TRUE';
    'NC'<6>:
      PIN_NUMBER='(13)';
      PINUSE='NC';
      NO_LOAD_CHECK='BOTH';
      NO_IO_CHECK='BOTH';
      ALLOW_CONNECT='TRUE';
    'NC'<5>:
      PIN_NUMBER='(12)';
      PINUSE='NC';
      NO_LOAD_CHECK='BOTH';
      NO_IO_CHECK='BOTH';
      ALLOW_CONNECT='TRUE';
    'NC'<4>:
      PIN_NUMBER='(11)';
      PINUSE='NC';
      NO_LOAD_CHECK='BOTH';
      NO_IO_CHECK='BOTH';
      ALLOW_CONNECT='TRUE';
    'NC'<3>:
      PIN_NUMBER='(6)';
      PINUSE='NC';
      NO_LOAD_CHECK='BOTH';
      NO_IO_CHECK='BOTH';
      ALLOW_CONNECT='TRUE';
    'NC'<2>:
      PIN_NUMBER='(5)';
      PINUSE='NC';
      NO_LOAD_CHECK='BOTH';
      NO_IO_CHECK='BOTH';
      ALLOW_CONNECT='TRUE';
    'NC'<1>:
      PIN_NUMBER='(4)';
      PINUSE='NC';
      NO_LOAD_CHECK='BOTH';
      NO_IO_CHECK='BOTH';
      ALLOW_CONNECT='TRUE';
    'NC'<0>:
      PIN_NUMBER='(3)';
      PINUSE='NC';
      NO_LOAD_CHECK='BOTH';
      NO_IO_CHECK='BOTH';
      ALLOW_CONNECT='TRUE';
    'VCC':
      PIN_NUMBER='(2)';
      PINUSE='POWER';
      NO_LOAD_CHECK='Both';
      NO_IO_CHECK='Both';
      NO_ASSERT_CHECK='TRUE';
      NO_DIR_CHECK='TRUE';
      ALLOW_CONNECT='TRUE';
    'WP_N_IO2':
      PIN_NUMBER='(9)';
      BIDIRECTIONAL='TRUE';
      INPUT_LOAD='(-0.01,0.01)';
      OUTPUT_LOAD='(1.0,-1.0)';
  end_pin;
  body
    PART_NAME='W25Q128';
    PHYS_DES_PREFIX='U';
  end_body;
end_primitive;

primitive 'W25Q128_SOIC8','W25Q128_SKT8';
  pin
    'CLK':
      PIN_NUMBER='(6)';
      INPUT_LOAD='(-0.01,0.01)';
    'CS_N':
      PIN_NUMBER='(1)';
      INPUT_LOAD='(-0.01,0.01)';
    'DI':
      PIN_NUMBER='(5)';
      INPUT_LOAD='(-0.01,0.01)';
    'DO':
      PIN_NUMBER='(2)';
      OUTPUT_LOAD='(1.0,-1.0)';
    'GND':
      PIN_NUMBER='(4)';
      PINUSE='GROUND';
      NO_LOAD_CHECK='Both';
      NO_IO_CHECK='Both';
      NO_ASSERT_CHECK='TRUE';
      NO_DIR_CHECK='TRUE';
      ALLOW_CONNECT='TRUE';
    'HOLD_N':
      PIN_NUMBER='(7)';
      INPUT_LOAD='(-0.01,0.01)';
    'VCC':
      PIN_NUMBER='(8)';
      PINUSE='POWER';
      NO_LOAD_CHECK='Both';
      NO_IO_CHECK='Both';
      NO_ASSERT_CHECK='TRUE';
      NO_DIR_CHECK='TRUE';
      ALLOW_CONNECT='TRUE';
    'WP_N':
      PIN_NUMBER='(3)';
      INPUT_LOAD='(-0.01,0.01)';
  end_pin;
  body
    PART_NAME='W25Q128';
    PHYS_DES_PREFIX='U';
  end_body;
end_primitive;

primitive 'W25Q128_SOIC16','W25Q128_SKT16';
  pin
    'HOLD_N_IO'<3>:
      PIN_NUMBER='(1)';
      BIDIRECTIONAL='TRUE';
      INPUT_LOAD='(-0.01,0.01)';
      OUTPUT_LOAD='(1.0,-1.0)';
    'VCC':
      PIN_NUMBER='(2)';
      PINUSE='POWER';
      NO_LOAD_CHECK='Both';
      NO_IO_CHECK='Both';
      NO_ASSERT_CHECK='TRUE';
      NO_DIR_CHECK='TRUE';
      ALLOW_CONNECT='TRUE';
    'RESET_N':
      PIN_NUMBER='(3)';
      INPUT_LOAD='(-0.01,0.01)';
    'NC'<0>:
      PIN_NUMBER='(4)';
      PINUSE='NC';
      NO_LOAD_CHECK='Both';
      NO_IO_CHECK='Both';
      ALLOW_CONNECT='TRUE';
    'NC'<1>:
      PIN_NUMBER='(5)';
      PINUSE='NC';
      NO_LOAD_CHECK='Both';
      NO_IO_CHECK='Both';
      ALLOW_CONNECT='TRUE';
    'NC'<2>:
      PIN_NUMBER='(6)';
      PINUSE='NC';
      NO_LOAD_CHECK='Both';
      NO_IO_CHECK='Both';
      ALLOW_CONNECT='TRUE';
    'CS_N':
      PIN_NUMBER='(7)';
      INPUT_LOAD='(-0.01,0.01)';
    'DO_IO'<1>:
      PIN_NUMBER='(8)';
      BIDIRECTIONAL='TRUE';
      INPUT_LOAD='(-0.01,0.01)';
      OUTPUT_LOAD='(1.0,-1.0)';
    'WP_N_IO'<2>:
      PIN_NUMBER='(9)';
      BIDIRECTIONAL='TRUE';
      INPUT_LOAD='(-0.01,0.01)';
      OUTPUT_LOAD='(1.0,-1.0)';
    'GND':
      PIN_NUMBER='(10)';
      PINUSE='GROUND';
      NO_LOAD_CHECK='Both';
      NO_IO_CHECK='Both';
      NO_ASSERT_CHECK='TRUE';
      NO_DIR_CHECK='TRUE';
      ALLOW_CONNECT='TRUE';
    'NC'<3>:
      PIN_NUMBER='(11)';
      PINUSE='NC';
      NO_LOAD_CHECK='Both';
      NO_IO_CHECK='Both';
      ALLOW_CONNECT='TRUE';
    'NC'<4>:
      PIN_NUMBER='(12)';
      PINUSE='NC';
      NO_LOAD_CHECK='Both';
      NO_IO_CHECK='Both';
      ALLOW_CONNECT='TRUE';
    'NC'<5>:
      PIN_NUMBER='(13)';
      PINUSE='NC';
      NO_LOAD_CHECK='Both';
      NO_IO_CHECK='Both';
      ALLOW_CONNECT='TRUE';
    'NC'<6>:
      PIN_NUMBER='(14)';
      PINUSE='NC';
      NO_LOAD_CHECK='Both';
      NO_IO_CHECK='Both';
      ALLOW_CONNECT='TRUE';
    'DI_IO'<0>:
      PIN_NUMBER='(15)';
      BIDIRECTIONAL='TRUE';
      INPUT_LOAD='(-0.01,0.01)';
      OUTPUT_LOAD='(1.0,-1.0)';
    'CLK':
      PIN_NUMBER='(16)';
      INPUT_LOAD='(-0.01,0.01)';
  end_pin;
  body
    PART_NAME='W25Q128';
    PHYS_DES_PREFIX='U';
  end_body;
end_primitive;

primitive 'W25Q128_SM';
  pin
    'CLK':
      PIN_NUMBER='(6)';
      INPUT_LOAD='(-0.01,0.01)';
    'CS_N':
      PIN_NUMBER='(1)';
      INPUT_LOAD='(-0.01,0.01)';
    'DI_IO0':
      PIN_NUMBER='(5)';
      BIDIRECTIONAL='TRUE';
      INPUT_LOAD='(-0.01,0.01)';
      OUTPUT_LOAD='(1.0,-1.0)';
    'DO_IO1':
      PIN_NUMBER='(2)';
      BIDIRECTIONAL='TRUE';
      INPUT_LOAD='(-0.01,0.01)';
      OUTPUT_LOAD='(1.0,-1.0)';
    'GND':
      PIN_NUMBER='(4)';
      PINUSE='GROUND';
      NO_LOAD_CHECK='Both';
      NO_IO_CHECK='Both';
      NO_ASSERT_CHECK='TRUE';
      NO_DIR_CHECK='TRUE';
      ALLOW_CONNECT='TRUE';
    'HOLD_N_RESET_N_IO3':
      PIN_NUMBER='(7)';
      BIDIRECTIONAL='TRUE';
      INPUT_LOAD='(-0.01,0.01)';
      OUTPUT_LOAD='(1.0,-1.0)';
    'VCC':
      PIN_NUMBER='(8)';
      PINUSE='POWER';
      NO_LOAD_CHECK='Both';
      NO_IO_CHECK='Both';
      NO_ASSERT_CHECK='TRUE';
      NO_DIR_CHECK='TRUE';
      ALLOW_CONNECT='TRUE';
    'WP_N_IO2':
      PIN_NUMBER='(3)';
      BIDIRECTIONAL='TRUE';
      INPUT_LOAD='(-0.01,0.01)';
      OUTPUT_LOAD='(1.0,-1.0)';
  end_pin;
  body
    PART_NAME='W25Q128';
    PHYS_DES_PREFIX='U';
  end_body;
end_primitive;

END.
